(kicad_pcb
	(version 20241229)
	(generator "pcbnew")
	(generator_version "9.0")
	(general
		(thickness 1.599998)
		(legacy_teardrops no)
	)
	(paper "A4")
	(title_block
		(title "Artix - Datacenter Secure Control Module (DC-SCM)")
		(date "2024-11-06")
		(rev "1.1.3")
		(comment 9 "footprints 119-122 of 544")
	)
	(layers
		(0 "F.Cu" signal)
		(4 "In1.Cu" signal)
		(6 "In2.Cu" signal)
		(8 "In3.Cu" signal)
		(10 "In4.Cu" signal)
		(12 "In5.Cu" signal)
		(14 "In6.Cu" signal)
		(2 "B.Cu" signal)
		(9 "F.Adhes" user "F.Adhesive")
		(11 "B.Adhes" user "B.Adhesive")
		(13 "F.Paste" user)
		(15 "B.Paste" user)
		(5 "F.SilkS" user "F.Silkscreen")
		(7 "B.SilkS" user "B.Silkscreen")
		(1 "F.Mask" user)
		(3 "B.Mask" user)
		(17 "Dwgs.User" user "User.Drawings")
		(19 "Cmts.User" user "User.Comments")
		(21 "Eco1.User" user "User.Eco1")
		(23 "Eco2.User" user "User.Eco2")
		(25 "Edge.Cuts" user)
		(27 "Margin" user)
		(31 "F.CrtYd" user "F.Courtyard")
		(29 "B.CrtYd" user "B.Courtyard")
		(35 "F.Fab" user)
		(33 "B.Fab" user)
	)
	(footprint "antmicro-footprints:SOT-23-3"
		(layer "F.Cu")
		(at 121.375 72.08)
		(property "Reference" "Q15"
			(at 0.75 -0.655 0)
			(layer "F.SilkS")
			(effects
				(font
					(size 0.7 0.7)
					(thickness 0.15)
				)
				(justify left bottom)
			)
		)
		(property "Value" "2N7002_SOT-23-3"
			(at -1.9 2.7 0)
			(layer "F.Fab")
			(effects
				(font
					(size 0.7 0.7)
					(thickness 0.15)
				)
				(justify left bottom)
			)
		)
		(property "Datasheet" "https://www.onsemi.com/pub/Collateral/NDS7002A-D.PDF"
			(at 0 0 0)
			(layer "F.Fab")
			(hide yes)
			(effects
				(font
					(size 1.27 1.27)
					(thickness 0.15)
				)
			)
		)
		(property "Description" "Power MOSFET, N Channel, 60 V, 115 mA, 1.2 ohm, SOT-23, Surface Mount"
			(at 0 0 0)
			(layer "F.Fab")
			(hide yes)
			(effects
				(font
					(size 1.27 1.27)
					(thickness 0.15)
				)
			)
		)
		(property "Author" "Antmicro"
			(at 0 0 0)
			(layer "F.Fab")
			(hide yes)
			(effects
				(font
					(size 1 1)
					(thickness 0.15)
				)
			)
		)
		(property "License" "Apache-2.0"
			(at 0 0 0)
			(layer "F.Fab")
			(hide yes)
			(effects
				(font
					(size 1 1)
					(thickness 0.15)
				)
			)
		)
		(property "MPN" "2N7002"
			(at 0 0 0)
			(layer "F.Fab")
			(hide yes)
			(effects
				(font
					(size 1 1)
					(thickness 0.15)
				)
			)
		)
		(property "Manufacturer" "ON Semiconductor"
			(at 0 0 0)
			(layer "F.Fab")
			(hide yes)
			(effects
				(font
					(size 1 1)
					(thickness 0.15)
				)
			)
		)
		(sheetname "/FPGA banks 34-35 & CFG/")
		(sheetfile "fpga-banks-34-25-cfg.kicad_sch")
		(attr smd)
		(fp_line
			(start -1.45 -1.35)
			(end -0.85 -1.35)
			(stroke
				(width 0.15)
				(type solid)
			)
			(layer "F.SilkS")
		)
		(fp_line
			(start -0.85 -1.35)
			(end -0.7 -1.5)
			(stroke
				(width 0.15)
				(type solid)
			)
			(layer "F.SilkS")
		)
		(fp_line
			(start -0.7 1.5)
			(end -0.7 1.35)
			(stroke
				(width 0.15)
				(type solid)
			)
			(layer "F.SilkS")
		)
		(fp_line
			(start 0.7 -1.5)
			(end -0.7 -1.5)
			(stroke
				(width 0.15)
				(type solid)
			)
			(layer "F.SilkS")
		)
		(fp_line
			(start 0.7 -0.4)
			(end 0.7 -1.5)
			(stroke
				(width 0.15)
				(type solid)
			)
			(layer "F.SilkS")
		)
		(fp_line
			(start 0.7 0.4)
			(end 0.7 1.5)
			(stroke
				(width 0.15)
				(type solid)
			)
			(layer "F.SilkS")
		)
		(fp_line
			(start 0.7 1.5)
			(end -0.7 1.5)
			(stroke
				(width 0.15)
				(type solid)
			)
			(layer "F.SilkS")
		)
		(fp_line
			(start -1.75 -0.5)
			(end -1.75 -1.4)
			(stroke
				(width 0.05)
				(type solid)
			)
			(layer "F.CrtYd")
		)
		(fp_line
			(start -1.75 0.5)
			(end -0.85 0.5)
			(stroke
				(width 0.05)
				(type solid)
			)
			(layer "F.CrtYd")
		)
		(fp_line
			(start -1.75 1.4)
			(end -1.75 0.5)
			(stroke
				(width 0.05)
				(type solid)
			)
			(layer "F.CrtYd")
		)
		(fp_line
			(start -0.9 -1.6)
			(end -0.9 -1.4)
			(stroke
				(width 0.05)
				(type solid)
			)
			(layer "F.CrtYd")
		)
		(fp_line
			(start -0.9 -1.6)
			(end 0.825 -1.6)
			(stroke
				(width 0.05)
				(type solid)
			)
			(layer "F.CrtYd")
		)
		(fp_line
			(start -0.9 -1.4)
			(end -1.75 -1.4)
			(stroke
				(width 0.05)
				(type solid)
			)
			(layer "F.CrtYd")
		)
		(fp_line
			(start -0.85 -0.5)
			(end -1.75 -0.5)
			(stroke
				(width 0.05)
				(type solid)
			)
			(layer "F.CrtYd")
		)
		(fp_line
			(start -0.85 0.5)
			(end -0.85 -0.5)
			(stroke
				(width 0.05)
				(type solid)
			)
			(layer "F.CrtYd")
		)
		(fp_line
			(start -0.85 1.4)
			(end -1.75 1.4)
			(stroke
				(width 0.05)
				(type solid)
			)
			(layer "F.CrtYd")
		)
		(fp_line
			(start -0.85 1.65)
			(end -0.85 1.4)
			(stroke
				(width 0.05)
				(type solid)
			)
			(layer "F.CrtYd")
		)
		(fp_line
			(start 0.825 -1.6)
			(end 0.825 -0.45)
			(stroke
				(width 0.05)
				(type solid)
			)
			(layer "F.CrtYd")
		)
		(fp_line
			(start 0.825 -0.45)
			(end 1.75 -0.45)
			(stroke
				(width 0.05)
				(type solid)
			)
			(layer "F.CrtYd")
		)
		(fp_line
			(start 0.85 0.45)
			(end 0.85 1.65)
			(stroke
				(width 0.05)
				(type solid)
			)
			(layer "F.CrtYd")
		)
		(fp_line
			(start 0.85 1.65)
			(end -0.85 1.65)
			(stroke
				(width 0.05)
				(type solid)
			)
			(layer "F.CrtYd")
		)
		(fp_line
			(start 1.75 -0.45)
			(end 1.75 0.45)
			(stroke
				(width 0.05)
				(type solid)
			)
			(layer "F.CrtYd")
		)
		(fp_line
			(start 1.75 0.45)
			(end 0.85 0.45)
			(stroke
				(width 0.05)
				(type solid)
			)
			(layer "F.CrtYd")
		)
		(fp_line
			(start -0.712 -1.325)
			(end -0.712 1.523)
			(stroke
				(width 0.15)
				(type solid)
			)
			(layer "F.Fab")
		)
		(fp_line
			(start -0.712 1.519)
			(end 0.688 1.519)
			(stroke
				(width 0.15)
				(type solid)
			)
			(layer "F.Fab")
		)
		(fp_line
			(start -0.437 -1.526)
			(end -0.712 -1.325)
			(stroke
				(width 0.15)
				(type solid)
			)
			(layer "F.Fab")
		)
		(fp_line
			(start -0.437 -1.526)
			(end 0.688 -1.526)
			(stroke
				(width 0.15)
				(type solid)
			)
			(layer "F.Fab")
		)
		(fp_line
			(start 0.688 1.519)
			(end 0.688 -1.52)
			(stroke
				(width 0.15)
				(type solid)
			)
			(layer "F.Fab")
		)
		(pad "1" smd roundrect
			(at -1.1 -0.951)
			(size 1 0.6)
			(layers "F.Cu" "F.Mask" "F.Paste")
			(roundrect_rratio 0.15)
			(net 317 "USR_LED1")
			(pinfunction "G")
			(pintype "input")
		)
		(pad "2" smd roundrect
			(at -1.1 0.949)
			(size 1 0.6)
			(layers "F.Cu" "F.Mask" "F.Paste")
			(roundrect_rratio 0.15)
			(net 1 "GND")
			(pinfunction "S")
			(pintype "passive")
		)
		(pad "3" smd roundrect
			(at 1.1 -0.0005)
			(size 1 0.6)
			(layers "F.Cu" "F.Mask" "F.Paste")
			(roundrect_rratio 0.15)
			(net 305 "Net-(D12-C)")
			(pinfunction "D")
			(pintype "passive")
		)
	)
	(footprint "antmicro-footprints:SOT-23-3"
		(layer "F.Cu")
		(at 121.35 76.055)
		(property "Reference" "Q16"
			(at 0.75 -0.655 0)
			(layer "F.SilkS")
			(effects
				(font
					(size 0.7 0.7)
					(thickness 0.15)
				)
				(justify left bottom)
			)
		)
		(property "Value" "2N7002_SOT-23-3"
			(at -1.9 2.7 0)
			(layer "F.Fab")
			(effects
				(font
					(size 0.7 0.7)
					(thickness 0.15)
				)
				(justify left bottom)
			)
		)
		(property "Datasheet" "https://www.onsemi.com/pub/Collateral/NDS7002A-D.PDF"
			(at 0 0 0)
			(layer "F.Fab")
			(hide yes)
			(effects
				(font
					(size 1.27 1.27)
					(thickness 0.15)
				)
			)
		)
		(property "Description" "Power MOSFET, N Channel, 60 V, 115 mA, 1.2 ohm, SOT-23, Surface Mount"
			(at 0 0 0)
			(layer "F.Fab")
			(hide yes)
			(effects
				(font
					(size 1.27 1.27)
					(thickness 0.15)
				)
			)
		)
		(property "Author" "Antmicro"
			(at 0 0 0)
			(layer "F.Fab")
			(hide yes)
			(effects
				(font
					(size 1 1)
					(thickness 0.15)
				)
			)
		)
		(property "License" "Apache-2.0"
			(at 0 0 0)
			(layer "F.Fab")
			(hide yes)
			(effects
				(font
					(size 1 1)
					(thickness 0.15)
				)
			)
		)
		(property "MPN" "2N7002"
			(at 0 0 0)
			(layer "F.Fab")
			(hide yes)
			(effects
				(font
					(size 1 1)
					(thickness 0.15)
				)
			)
		)
		(property "Manufacturer" "ON Semiconductor"
			(at 0 0 0)
			(layer "F.Fab")
			(hide yes)
			(effects
				(font
					(size 1 1)
					(thickness 0.15)
				)
			)
		)
		(sheetname "/FPGA banks 34-35 & CFG/")
		(sheetfile "fpga-banks-34-25-cfg.kicad_sch")
		(attr smd)
		(fp_line
			(start -1.45 -1.35)
			(end -0.85 -1.35)
			(stroke
				(width 0.15)
				(type solid)
			)
			(layer "F.SilkS")
		)
		(fp_line
			(start -0.85 -1.35)
			(end -0.7 -1.5)
			(stroke
				(width 0.15)
				(type solid)
			)
			(layer "F.SilkS")
		)
		(fp_line
			(start -0.7 1.5)
			(end -0.7 1.35)
			(stroke
				(width 0.15)
				(type solid)
			)
			(layer "F.SilkS")
		)
		(fp_line
			(start 0.7 -1.5)
			(end -0.7 -1.5)
			(stroke
				(width 0.15)
				(type solid)
			)
			(layer "F.SilkS")
		)
		(fp_line
			(start 0.7 -0.4)
			(end 0.7 -1.5)
			(stroke
				(width 0.15)
				(type solid)
			)
			(layer "F.SilkS")
		)
		(fp_line
			(start 0.7 0.4)
			(end 0.7 1.5)
			(stroke
				(width 0.15)
				(type solid)
			)
			(layer "F.SilkS")
		)
		(fp_line
			(start 0.7 1.5)
			(end -0.7 1.5)
			(stroke
				(width 0.15)
				(type solid)
			)
			(layer "F.SilkS")
		)
		(fp_line
			(start -1.75 -0.5)
			(end -1.75 -1.4)
			(stroke
				(width 0.05)
				(type solid)
			)
			(layer "F.CrtYd")
		)
		(fp_line
			(start -1.75 0.5)
			(end -0.85 0.5)
			(stroke
				(width 0.05)
				(type solid)
			)
			(layer "F.CrtYd")
		)
		(fp_line
			(start -1.75 1.4)
			(end -1.75 0.5)
			(stroke
				(width 0.05)
				(type solid)
			)
			(layer "F.CrtYd")
		)
		(fp_line
			(start -0.9 -1.6)
			(end -0.9 -1.4)
			(stroke
				(width 0.05)
				(type solid)
			)
			(layer "F.CrtYd")
		)
		(fp_line
			(start -0.9 -1.6)
			(end 0.825 -1.6)
			(stroke
				(width 0.05)
				(type solid)
			)
			(layer "F.CrtYd")
		)
		(fp_line
			(start -0.9 -1.4)
			(end -1.75 -1.4)
			(stroke
				(width 0.05)
				(type solid)
			)
			(layer "F.CrtYd")
		)
		(fp_line
			(start -0.85 -0.5)
			(end -1.75 -0.5)
			(stroke
				(width 0.05)
				(type solid)
			)
			(layer "F.CrtYd")
		)
		(fp_line
			(start -0.85 0.5)
			(end -0.85 -0.5)
			(stroke
				(width 0.05)
				(type solid)
			)
			(layer "F.CrtYd")
		)
		(fp_line
			(start -0.85 1.4)
			(end -1.75 1.4)
			(stroke
				(width 0.05)
				(type solid)
			)
			(layer "F.CrtYd")
		)
		(fp_line
			(start -0.85 1.65)
			(end -0.85 1.4)
			(stroke
				(width 0.05)
				(type solid)
			)
			(layer "F.CrtYd")
		)
		(fp_line
			(start 0.825 -1.6)
			(end 0.825 -0.45)
			(stroke
				(width 0.05)
				(type solid)
			)
			(layer "F.CrtYd")
		)
		(fp_line
			(start 0.825 -0.45)
			(end 1.75 -0.45)
			(stroke
				(width 0.05)
				(type solid)
			)
			(layer "F.CrtYd")
		)
		(fp_line
			(start 0.85 0.45)
			(end 0.85 1.65)
			(stroke
				(width 0.05)
				(type solid)
			)
			(layer "F.CrtYd")
		)
		(fp_line
			(start 0.85 1.65)
			(end -0.85 1.65)
			(stroke
				(width 0.05)
				(type solid)
			)
			(layer "F.CrtYd")
		)
		(fp_line
			(start 1.75 -0.45)
			(end 1.75 0.45)
			(stroke
				(width 0.05)
				(type solid)
			)
			(layer "F.CrtYd")
		)
		(fp_line
			(start 1.75 0.45)
			(end 0.85 0.45)
			(stroke
				(width 0.05)
				(type solid)
			)
			(layer "F.CrtYd")
		)
		(fp_line
			(start -0.712 -1.325)
			(end -0.712 1.523)
			(stroke
				(width 0.15)
				(type solid)
			)
			(layer "F.Fab")
		)
		(fp_line
			(start -0.712 1.519)
			(end 0.688 1.519)
			(stroke
				(width 0.15)
				(type solid)
			)
			(layer "F.Fab")
		)
		(fp_line
			(start -0.437 -1.526)
			(end -0.712 -1.325)
			(stroke
				(width 0.15)
				(type solid)
			)
			(layer "F.Fab")
		)
		(fp_line
			(start -0.437 -1.526)
			(end 0.688 -1.526)
			(stroke
				(width 0.15)
				(type solid)
			)
			(layer "F.Fab")
		)
		(fp_line
			(start 0.688 1.519)
			(end 0.688 -1.52)
			(stroke
				(width 0.15)
				(type solid)
			)
			(layer "F.Fab")
		)
		(pad "1" smd roundrect
			(at -1.1 -0.951)
			(size 1 0.6)
			(layers "F.Cu" "F.Mask" "F.Paste")
			(roundrect_rratio 0.15)
			(net 318 "USR_LED2")
			(pinfunction "G")
			(pintype "input")
		)
		(pad "2" smd roundrect
			(at -1.1 0.949)
			(size 1 0.6)
			(layers "F.Cu" "F.Mask" "F.Paste")
			(roundrect_rratio 0.15)
			(net 1 "GND")
			(pinfunction "S")
			(pintype "passive")
		)
		(pad "3" smd roundrect
			(at 1.1 -0.0005)
			(size 1 0.6)
			(layers "F.Cu" "F.Mask" "F.Paste")
			(roundrect_rratio 0.15)
			(net 309 "Net-(D13-C)")
			(pinfunction "D")
			(pintype "passive")
		)
	)
	(footprint "antmicro-footprints:R_0402_1005Metric"
		(layer "F.Cu")
		(at 138.975 63.705 -90)
		(descr "Resistor SMD 0402")
		(tags "resistor SMD 0402")
		(property "Reference" "R130"
			(at -1.105 -5.725 90)
			(layer "F.SilkS")
			(effects
				(font
					(size 0.7 0.7)
					(thickness 0.15)
				)
				(justify right bottom)
			)
		)
		(property "Value" "R_1k_0402"
			(at 0 1.4 90)
			(layer "F.Fab")
			(effects
				(font
					(size 0.7 0.7)
					(thickness 0.15)
				)
				(justify right bottom)
			)
		)
		(property "Datasheet" "https://www.bourns.com/docs/product-datasheets/cr.pdf"
			(at 0 0 270)
			(layer "F.Fab")
			(hide yes)
			(effects
				(font
					(size 1.27 1.27)
					(thickness 0.15)
				)
			)
		)
		(property "Description" "SMD Chip Resistor, 1 kohm, ± 1%, 63 mW, 0402 [1005 Metric], Thick Film, General Purpose"
			(at 0 0 270)
			(layer "F.Fab")
			(hide yes)
			(effects
				(font
					(size 1.27 1.27)
					(thickness 0.15)
				)
			)
		)
		(property "Author" "Antmicro"
			(at 75.27 202.68 0)
			(layer "F.Fab")
			(hide yes)
			(effects
				(font
					(size 1 1)
					(thickness 0.15)
				)
			)
		)
		(property "License" "Apache-2.0"
			(at 75.27 202.68 0)
			(layer "F.Fab")
			(hide yes)
			(effects
				(font
					(size 1 1)
					(thickness 0.15)
				)
			)
		)
		(property "MPN" "CR0402-FX-1001GLF"
			(at 75.27 202.68 0)
			(layer "F.Fab")
			(hide yes)
			(effects
				(font
					(size 1 1)
					(thickness 0.15)
				)
			)
		)
		(property "Manufacturer" "Bourns"
			(at 75.27 202.68 0)
			(layer "F.Fab")
			(hide yes)
			(effects
				(font
					(size 1 1)
					(thickness 0.15)
				)
			)
		)
		(property "Tolerance" "1%"
			(at 75.27 202.68 0)
			(layer "F.Fab")
			(hide yes)
			(effects
				(font
					(size 1 1)
					(thickness 0.15)
				)
			)
		)
		(property "Val" "1k"
			(at 75.27 202.68 0)
			(layer "F.Fab")
			(hide yes)
			(effects
				(font
					(size 1 1)
					(thickness 0.15)
				)
			)
		)
		(sheetname "/FPGA banks 34-35 & CFG/")
		(sheetfile "fpga-banks-34-25-cfg.kicad_sch")
		(attr smd)
		(fp_rect
			(start -0.925 -0.47)
			(end 0.925 0.47)
			(stroke
				(width 0.05)
				(type default)
			)
			(fill no)
			(layer "F.CrtYd")
		)
		(fp_rect
			(start -0.5 -0.25)
			(end 0.5 0.25)
			(stroke
				(width 0.15)
				(type solid)
			)
			(fill no)
			(layer "F.Fab")
		)
		(pad "1" smd roundrect
			(at -0.48 0 270)
			(size 0.59 0.64)
			(layers "F.Cu" "F.Mask" "F.Paste")
			(roundrect_rratio 0.25)
			(net 286 "Net-(D11-A)")
			(pintype "passive")
		)
		(pad "2" smd roundrect
			(at 0.48 0 270)
			(size 0.59 0.64)
			(layers "F.Cu" "F.Mask" "F.Paste")
			(roundrect_rratio 0.25)
			(net 2 "VCC3V3")
			(pintype "passive")
		)
	)
	(footprint "antmicro-footprints:R_0402_1005Metric"
		(layer "F.Cu")
		(at 141.025 63.705 -90)
		(descr "Resistor SMD 0402")
		(tags "resistor SMD 0402")
		(property "Reference" "R131"
			(at -1.105 -4.775 90)
			(layer "F.SilkS")
			(effects
				(font
					(size 0.7 0.7)
					(thickness 0.15)
				)
				(justify right bottom)
			)
		)
		(property "Value" "R_1k_0402"
			(at 0 1.4 90)
			(layer "F.Fab")
			(effects
				(font
					(size 0.7 0.7)
					(thickness 0.15)
				)
				(justify right bottom)
			)
		)
		(property "Datasheet" "https://www.bourns.com/docs/product-datasheets/cr.pdf"
			(at 0 0 270)
			(layer "F.Fab")
			(hide yes)
			(effects
				(font
					(size 1.27 1.27)
					(thickness 0.15)
				)
			)
		)
		(property "Description" "SMD Chip Resistor, 1 kohm, ± 1%, 63 mW, 0402 [1005 Metric], Thick Film, General Purpose"
			(at 0 0 270)
			(layer "F.Fab")
			(hide yes)
			(effects
				(font
					(size 1.27 1.27)
					(thickness 0.15)
				)
			)
		)
		(property "Author" "Antmicro"
			(at 77.32 204.73 0)
			(layer "F.Fab")
			(hide yes)
			(effects
				(font
					(size 1 1)
					(thickness 0.15)
				)
			)
		)
		(property "License" "Apache-2.0"
			(at 77.32 204.73 0)
			(layer "F.Fab")
			(hide yes)
			(effects
				(font
					(size 1 1)
					(thickness 0.15)
				)
			)
		)
		(property "MPN" "CR0402-FX-1001GLF"
			(at 77.32 204.73 0)
			(layer "F.Fab")
			(hide yes)
			(effects
				(font
					(size 1 1)
					(thickness 0.15)
				)
			)
		)
		(property "Manufacturer" "Bourns"
			(at 77.32 204.73 0)
			(layer "F.Fab")
			(hide yes)
			(effects
				(font
					(size 1 1)
					(thickness 0.15)
				)
			)
		)
		(property "Tolerance" "1%"
			(at 77.32 204.73 0)
			(layer "F.Fab")
			(hide yes)
			(effects
				(font
					(size 1 1)
					(thickness 0.15)
				)
			)
		)
		(property "Val" "1k"
			(at 77.32 204.73 0)
			(layer "F.Fab")
			(hide yes)
			(effects
				(font
					(size 1 1)
					(thickness 0.15)
				)
			)
		)
		(sheetname "/FPGA banks 34-35 & CFG/")
		(sheetfile "fpga-banks-34-25-cfg.kicad_sch")
		(attr smd)
		(fp_rect
			(start -0.925 -0.47)
			(end 0.925 0.47)
			(stroke
				(width 0.05)
				(type default)
			)
			(fill no)
			(layer "F.CrtYd")
		)
		(fp_rect
			(start -0.5 -0.25)
			(end 0.5 0.25)
			(stroke
				(width 0.15)
				(type solid)
			)
			(fill no)
			(layer "F.Fab")
		)
		(pad "1" smd roundrect
			(at -0.48 0 270)
			(size 0.59 0.64)
			(layers "F.Cu" "F.Mask" "F.Paste")
			(roundrect_rratio 0.25)
			(net 307 "Net-(D12-A)")
			(pintype "passive")
		)
		(pad "2" smd roundrect
			(at 0.48 0 270)
			(size 0.59 0.64)
			(layers "F.Cu" "F.Mask" "F.Paste")
			(roundrect_rratio 0.25)
			(net 2 "VCC3V3")
			(pintype "passive")
		)
	)
)
